# Kria K26 Devboard — footprint library table
(fp_lib_table
  (lib (name "kria-k26-devboard-footprints")(type "KiCad")(uri "${KIPRJMOD}/lib/kria-k26-devboard-footprints/")(options "")(descr ""))
)
